(kicad_pcb
	(version 20221018)
	(generator pcbnew)
	(general
    (thickness 1.62)
  )
	(paper "A4")
	(title_block
    (title "ECP5 - Datacenter Secure Control Module (DC-SCM)")
    (date "2024-07-01")
    (rev "1.2.1")
		(comment 9 "footprints 320-327 of 506")
	)
	(layers
    (0 "F.Cu" signal)
    (1 "In1.Cu" power)
    (2 "In2.Cu" signal)
    (3 "In3.Cu" power)
    (4 "In4.Cu" power)
    (5 "In5.Cu" signal)
    (6 "In6.Cu" power)
    (31 "B.Cu" signal)
    (32 "B.Adhes" user "B.Adhesive")
    (33 "F.Adhes" user "F.Adhesive")
    (34 "B.Paste" user)
    (35 "F.Paste" user)
    (36 "B.SilkS" user "B.Silkscreen")
    (37 "F.SilkS" user "F.Silkscreen")
    (38 "B.Mask" user)
    (39 "F.Mask" user)
    (40 "Dwgs.User" user "User.Drawings")
    (41 "Cmts.User" user "User.Comments")
    (42 "Eco1.User" user "User.Eco1")
    (43 "Eco2.User" user "User.Eco2")
    (44 "Edge.Cuts" user)
    (45 "Margin" user)
    (46 "B.CrtYd" user "B.Courtyard")
    (47 "F.CrtYd" user "F.Courtyard")
    (48 "B.Fab" user)
    (49 "F.Fab" user)
  )
	(footprint "antmicro-footprints:C_0402_1005Metric" (layer "B.Cu")
    (at 105.95 115.15 -90)
    (descr "Capacitor SMD 0402")
    (tags "capacitor SMD 0402")
    (property "Author" "Antmicro")
    (property "Dielectric" "")
    (property "License" "Apache-2.0")
    (property "MPN" "C1005X5R1E474M050BB")
    (property "Manufacturer" "TDK")
    (property "Public" "False")
    (property "Sheetfile" "fpga-banks.kicad_sch")
    (property "Sheetname" "FPGA banks")
    (property "Val" "470n")
    (property "Voltage" "")
    (property "ki_description" "SMD Multilayer Ceramic Capacitor, 0.47 µF, 25 V, 0402 [1005 Metric], ± 20%, X5R, C")
    (property "ki_keywords" "0402, SMT, CAPACITOR, PASSIVE, CERAMIC, MLCC")
    (attr smd)
    (fp_text reference "C211" (at -4.3 0 90) (layer "B.SilkS")
        (effects (font (size 0.7 0.7) (thickness 0.127)) (justify mirror))
    )
    (fp_text value "C_470n_0402" (at 0 -1.17 90) (layer "B.Fab")
        (effects (font (size 1 1) (thickness 0.15)) (justify mirror))
    )
    (fp_text user "Author: Antmicro" (at -0.939 -3.399 90) (layer "B.Fab") hide
        (effects (font (size 0.7 0.7) (thickness 0.15)) (justify left bottom mirror))
    )
    (fp_text user "License: Apache-2.0" (at -0.939 -5.799 90) (layer "B.Fab") hide
        (effects (font (size 0.7 0.7) (thickness 0.15)) (justify left bottom mirror))
    )
    (fp_text user "${REFERENCE}" (at 0 0 90) (layer "B.Fab")
        (effects (font (size 0.25 0.25) (thickness 0.04)) (justify mirror))
    )
    (fp_rect (start -0.925 0.47) (end 0.925 -0.47)
      (stroke (width 0.05) (type default)) (fill none) (layer "B.CrtYd"))
    (fp_line (start -0.494 -0.248) (end -0.494 0.25)
      (stroke (width 0.15) (type solid)) (layer "B.Fab"))
    (fp_line (start -0.494 0.25) (end 0.504 0.25)
      (stroke (width 0.15) (type solid)) (layer "B.Fab"))
    (fp_line (start 0.504 -0.248) (end -0.494 -0.248)
      (stroke (width 0.15) (type solid)) (layer "B.Fab"))
    (fp_line (start 0.504 0.25) (end 0.504 -0.248)
      (stroke (width 0.15) (type solid)) (layer "B.Fab"))
    (pad "1" smd roundrect (at -0.48 0 270) (size 0.59 0.64) (layers "B.Cu" "B.Paste" "B.Mask") (roundrect_rratio 0.25)
      (net 2 "VCC3V3") (pintype "passive"))
    (pad "2" smd roundrect (at 0.48 0 270) (size 0.59 0.64) (layers "B.Cu" "B.Paste" "B.Mask") (roundrect_rratio 0.25)
      (net 1 "GND") (pintype "passive"))
  )
	(footprint "antmicro-footprints:C_0402_1005Metric" (layer "B.Cu")
    (at 111.25 125.8)
    (descr "Capacitor SMD 0402")
    (tags "capacitor SMD 0402")
    (property "Author" "Antmicro")
    (property "Dielectric" "")
    (property "License" "Apache-2.0")
    (property "MPN" "C1005X5R1E474M050BB")
    (property "Manufacturer" "TDK")
    (property "Public" "False")
    (property "Sheetfile" "fpga-banks.kicad_sch")
    (property "Sheetname" "FPGA banks")
    (property "Val" "470n")
    (property "Voltage" "")
    (property "ki_description" "SMD Multilayer Ceramic Capacitor, 0.47 µF, 25 V, 0402 [1005 Metric], ± 20%, X5R, C")
    (property "ki_keywords" "0402, SMT, CAPACITOR, PASSIVE, CERAMIC, MLCC")
    (attr smd)
    (fp_text reference "C212" (at 3.4 -0.05) (layer "B.SilkS")
        (effects (font (size 0.7 0.7) (thickness 0.127)) (justify mirror))
    )
    (fp_text value "C_470n_0402" (at 0 -1.17) (layer "B.Fab")
        (effects (font (size 1 1) (thickness 0.15)) (justify mirror))
    )
    (fp_text user "Author: Antmicro" (at -0.939 -3.399 180) (layer "B.Fab") hide
        (effects (font (size 0.7 0.7) (thickness 0.15)) (justify left bottom mirror))
    )
    (fp_text user "License: Apache-2.0" (at -0.939 -5.799 180) (layer "B.Fab") hide
        (effects (font (size 0.7 0.7) (thickness 0.15)) (justify left bottom mirror))
    )
    (fp_text user "${REFERENCE}" (at 0 0) (layer "B.Fab")
        (effects (font (size 0.25 0.25) (thickness 0.04)) (justify mirror))
    )
    (fp_rect (start -0.925 0.47) (end 0.925 -0.47)
      (stroke (width 0.05) (type default)) (fill none) (layer "B.CrtYd"))
    (fp_line (start -0.494 -0.248) (end -0.494 0.25)
      (stroke (width 0.15) (type solid)) (layer "B.Fab"))
    (fp_line (start -0.494 0.25) (end 0.504 0.25)
      (stroke (width 0.15) (type solid)) (layer "B.Fab"))
    (fp_line (start 0.504 -0.248) (end -0.494 -0.248)
      (stroke (width 0.15) (type solid)) (layer "B.Fab"))
    (fp_line (start 0.504 0.25) (end 0.504 -0.248)
      (stroke (width 0.15) (type solid)) (layer "B.Fab"))
    (pad "1" smd roundrect (at -0.48 0) (size 0.59 0.64) (layers "B.Cu" "B.Paste" "B.Mask") (roundrect_rratio 0.25)
      (net 2 "VCC3V3") (pintype "passive"))
    (pad "2" smd roundrect (at 0.48 0) (size 0.59 0.64) (layers "B.Cu" "B.Paste" "B.Mask") (roundrect_rratio 0.25)
      (net 1 "GND") (pintype "passive"))
  )
	(footprint "antmicro-footprints:C_0402_1005Metric" (layer "B.Cu")
    (at 105.95 113.2 90)
    (descr "Capacitor SMD 0402")
    (tags "capacitor SMD 0402")
    (property "Author" "Antmicro")
    (property "Dielectric" "")
    (property "License" "Apache-2.0")
    (property "MPN" "C1005X5R1E474M050BB")
    (property "Manufacturer" "TDK")
    (property "Public" "False")
    (property "Sheetfile" "fpga-banks.kicad_sch")
    (property "Sheetname" "FPGA banks")
    (property "Val" "470n")
    (property "Voltage" "")
    (property "ki_description" "SMD Multilayer Ceramic Capacitor, 0.47 µF, 25 V, 0402 [1005 Metric], ± 20%, X5R, C")
    (property "ki_keywords" "0402, SMT, CAPACITOR, PASSIVE, CERAMIC, MLCC")
    (attr smd)
    (fp_text reference "C213" (at 5.2 0 90) (layer "B.SilkS")
        (effects (font (size 0.7 0.7) (thickness 0.127)) (justify mirror))
    )
    (fp_text value "C_470n_0402" (at 0 -1.17 90) (layer "B.Fab")
        (effects (font (size 1 1) (thickness 0.15)) (justify mirror))
    )
    (fp_text user "${REFERENCE}" (at 0 0 90) (layer "B.Fab")
        (effects (font (size 0.25 0.25) (thickness 0.04)) (justify mirror))
    )
    (fp_text user "License: Apache-2.0" (at -0.939 -5.799 270) (layer "B.Fab") hide
        (effects (font (size 0.7 0.7) (thickness 0.15)) (justify left bottom mirror))
    )
    (fp_text user "Author: Antmicro" (at -0.939 -3.399 270) (layer "B.Fab") hide
        (effects (font (size 0.7 0.7) (thickness 0.15)) (justify left bottom mirror))
    )
    (fp_rect (start -0.925 0.47) (end 0.925 -0.47)
      (stroke (width 0.05) (type default)) (fill none) (layer "B.CrtYd"))
    (fp_line (start -0.494 -0.248) (end -0.494 0.25)
      (stroke (width 0.15) (type solid)) (layer "B.Fab"))
    (fp_line (start -0.494 0.25) (end 0.504 0.25)
      (stroke (width 0.15) (type solid)) (layer "B.Fab"))
    (fp_line (start 0.504 -0.248) (end -0.494 -0.248)
      (stroke (width 0.15) (type solid)) (layer "B.Fab"))
    (fp_line (start 0.504 0.25) (end 0.504 -0.248)
      (stroke (width 0.15) (type solid)) (layer "B.Fab"))
    (pad "1" smd roundrect (at -0.48 0 90) (size 0.59 0.64) (layers "B.Cu" "B.Paste" "B.Mask") (roundrect_rratio 0.25)
      (net 2 "VCC3V3") (pintype "passive"))
    (pad "2" smd roundrect (at 0.48 0 90) (size 0.59 0.64) (layers "B.Cu" "B.Paste" "B.Mask") (roundrect_rratio 0.25)
      (net 1 "GND") (pintype "passive"))
  )
	(footprint "antmicro-footprints:C_0402_1005Metric" (layer "B.Cu")
    (at 109.55 113.9)
    (descr "Capacitor SMD 0402")
    (tags "capacitor SMD 0402")
    (property "Author" "Antmicro")
    (property "Dielectric" "")
    (property "License" "Apache-2.0")
    (property "MPN" "C1005X5R1E474M050BB")
    (property "Manufacturer" "TDK")
    (property "Public" "False")
    (property "Sheetfile" "fpga-banks.kicad_sch")
    (property "Sheetname" "FPGA banks")
    (property "Val" "470n")
    (property "Voltage" "")
    (property "ki_description" "SMD Multilayer Ceramic Capacitor, 0.47 µF, 25 V, 0402 [1005 Metric], ± 20%, X5R, C")
    (property "ki_keywords" "0402, SMT, CAPACITOR, PASSIVE, CERAMIC, MLCC")
    (attr smd)
    (fp_text reference "C214" (at 2.8 0.05) (layer "B.SilkS")
        (effects (font (size 0.7 0.7) (thickness 0.127)) (justify mirror))
    )
    (fp_text value "C_470n_0402" (at 0 -1.17) (layer "B.Fab")
        (effects (font (size 1 1) (thickness 0.15)) (justify mirror))
    )
    (fp_text user "${REFERENCE}" (at 0 0) (layer "B.Fab")
        (effects (font (size 0.25 0.25) (thickness 0.04)) (justify mirror))
    )
    (fp_text user "License: Apache-2.0" (at -0.939 -5.799 180) (layer "B.Fab") hide
        (effects (font (size 0.7 0.7) (thickness 0.15)) (justify left bottom mirror))
    )
    (fp_text user "Author: Antmicro" (at -0.939 -3.399 180) (layer "B.Fab") hide
        (effects (font (size 0.7 0.7) (thickness 0.15)) (justify left bottom mirror))
    )
    (fp_rect (start -0.925 0.47) (end 0.925 -0.47)
      (stroke (width 0.05) (type default)) (fill none) (layer "B.CrtYd"))
    (fp_line (start -0.494 -0.248) (end -0.494 0.25)
      (stroke (width 0.15) (type solid)) (layer "B.Fab"))
    (fp_line (start -0.494 0.25) (end 0.504 0.25)
      (stroke (width 0.15) (type solid)) (layer "B.Fab"))
    (fp_line (start 0.504 -0.248) (end -0.494 -0.248)
      (stroke (width 0.15) (type solid)) (layer "B.Fab"))
    (fp_line (start 0.504 0.25) (end 0.504 -0.248)
      (stroke (width 0.15) (type solid)) (layer "B.Fab"))
    (pad "1" smd roundrect (at -0.48 0) (size 0.59 0.64) (layers "B.Cu" "B.Paste" "B.Mask") (roundrect_rratio 0.25)
      (net 2 "VCC3V3") (pintype "passive"))
    (pad "2" smd roundrect (at 0.48 0) (size 0.59 0.64) (layers "B.Cu" "B.Paste" "B.Mask") (roundrect_rratio 0.25)
      (net 1 "GND") (pintype "passive"))
  )
	(footprint "antmicro-footprints:C_0402_1005Metric" (layer "B.Cu")
    (at 106.95 113.75 90)
    (descr "Capacitor SMD 0402")
    (tags "capacitor SMD 0402")
    (property "Author" "Antmicro")
    (property "Dielectric" "")
    (property "License" "Apache-2.0")
    (property "MPN" "C1005X5R1E474M050BB")
    (property "Manufacturer" "TDK")
    (property "Public" "False")
    (property "Sheetfile" "fpga-banks.kicad_sch")
    (property "Sheetname" "FPGA banks")
    (property "Val" "470n")
    (property "Voltage" "")
    (property "ki_description" "SMD Multilayer Ceramic Capacitor, 0.47 µF, 25 V, 0402 [1005 Metric], ± 20%, X5R, C")
    (property "ki_keywords" "0402, SMT, CAPACITOR, PASSIVE, CERAMIC, MLCC")
    (attr smd)
    (fp_text reference "C215" (at 2.4 0.1 90) (layer "B.SilkS")
        (effects (font (size 0.7 0.7) (thickness 0.127)) (justify mirror))
    )
    (fp_text value "C_470n_0402" (at 0 -1.17 90) (layer "B.Fab")
        (effects (font (size 1 1) (thickness 0.15)) (justify mirror))
    )
    (fp_text user "License: Apache-2.0" (at -0.939 -5.799 270) (layer "B.Fab") hide
        (effects (font (size 0.7 0.7) (thickness 0.15)) (justify left bottom mirror))
    )
    (fp_text user "Author: Antmicro" (at -0.939 -3.399 270) (layer "B.Fab") hide
        (effects (font (size 0.7 0.7) (thickness 0.15)) (justify left bottom mirror))
    )
    (fp_text user "${REFERENCE}" (at 0 0 90) (layer "B.Fab")
        (effects (font (size 0.25 0.25) (thickness 0.04)) (justify mirror))
    )
    (fp_rect (start -0.925 0.47) (end 0.925 -0.47)
      (stroke (width 0.05) (type default)) (fill none) (layer "B.CrtYd"))
    (fp_line (start -0.494 -0.248) (end -0.494 0.25)
      (stroke (width 0.15) (type solid)) (layer "B.Fab"))
    (fp_line (start -0.494 0.25) (end 0.504 0.25)
      (stroke (width 0.15) (type solid)) (layer "B.Fab"))
    (fp_line (start 0.504 -0.248) (end -0.494 -0.248)
      (stroke (width 0.15) (type solid)) (layer "B.Fab"))
    (fp_line (start 0.504 0.25) (end 0.504 -0.248)
      (stroke (width 0.15) (type solid)) (layer "B.Fab"))
    (pad "1" smd roundrect (at -0.48 0 90) (size 0.59 0.64) (layers "B.Cu" "B.Paste" "B.Mask") (roundrect_rratio 0.25)
      (net 2 "VCC3V3") (pintype "passive"))
    (pad "2" smd roundrect (at 0.48 0 90) (size 0.59 0.64) (layers "B.Cu" "B.Paste" "B.Mask") (roundrect_rratio 0.25)
      (net 1 "GND") (pintype "passive"))
  )
	(footprint "antmicro-footprints:C_0402_1005Metric" (layer "B.Cu")
    (at 97.6 125.65 180)
    (descr "Capacitor SMD 0402")
    (tags "capacitor SMD 0402")
    (property "Author" "Antmicro")
    (property "Dielectric" "")
    (property "License" "Apache-2.0")
    (property "MPN" "C1005X5R1E474M050BB")
    (property "Manufacturer" "TDK")
    (property "Public" "False")
    (property "Sheetfile" "fpga-banks.kicad_sch")
    (property "Sheetname" "FPGA banks")
    (property "Val" "470n")
    (property "Voltage" "")
    (property "ki_description" "SMD Multilayer Ceramic Capacitor, 0.47 µF, 25 V, 0402 [1005 Metric], ± 20%, X5R, C")
    (property "ki_keywords" "0402, SMT, CAPACITOR, PASSIVE, CERAMIC, MLCC")
    (attr smd)
    (fp_text reference "C218" (at 2.3 -0.2) (layer "B.SilkS")
        (effects (font (size 0.7 0.7) (thickness 0.127)) (justify mirror))
    )
    (fp_text value "C_470n_0402" (at 0 -1.17) (layer "B.Fab")
        (effects (font (size 1 1) (thickness 0.15)) (justify mirror))
    )
    (fp_text user "${REFERENCE}" (at 0 0) (layer "B.Fab")
        (effects (font (size 0.25 0.25) (thickness 0.04)) (justify mirror))
    )
    (fp_text user "Author: Antmicro" (at -0.939 -3.399) (layer "B.Fab") hide
        (effects (font (size 0.7 0.7) (thickness 0.15)) (justify left bottom mirror))
    )
    (fp_text user "License: Apache-2.0" (at -0.939 -5.799) (layer "B.Fab") hide
        (effects (font (size 0.7 0.7) (thickness 0.15)) (justify left bottom mirror))
    )
    (fp_rect (start -0.925 0.47) (end 0.925 -0.47)
      (stroke (width 0.05) (type default)) (fill none) (layer "B.CrtYd"))
    (fp_line (start -0.494 -0.248) (end -0.494 0.25)
      (stroke (width 0.15) (type solid)) (layer "B.Fab"))
    (fp_line (start -0.494 0.25) (end 0.504 0.25)
      (stroke (width 0.15) (type solid)) (layer "B.Fab"))
    (fp_line (start 0.504 -0.248) (end -0.494 -0.248)
      (stroke (width 0.15) (type solid)) (layer "B.Fab"))
    (fp_line (start 0.504 0.25) (end 0.504 -0.248)
      (stroke (width 0.15) (type solid)) (layer "B.Fab"))
    (pad "1" smd roundrect (at -0.48 0 180) (size 0.59 0.64) (layers "B.Cu" "B.Paste" "B.Mask") (roundrect_rratio 0.25)
      (net 2 "VCC3V3") (pintype "passive"))
    (pad "2" smd roundrect (at 0.48 0 180) (size 0.59 0.64) (layers "B.Cu" "B.Paste" "B.Mask") (roundrect_rratio 0.25)
      (net 1 "GND") (pintype "passive"))
  )
	(footprint "antmicro-footprints:C_0402_1005Metric" (layer "B.Cu")
    (at 111.2 118.15)
    (descr "Capacitor SMD 0402")
    (tags "capacitor SMD 0402")
    (property "Author" "Antmicro")
    (property "Dielectric" "")
    (property "License" "Apache-2.0")
    (property "MPN" "GRM155R61A475MEAAD")
    (property "Manufacturer" "Murata")
    (property "Public" "False")
    (property "Sheetfile" "fpga-banks.kicad_sch")
    (property "Sheetname" "FPGA banks")
    (property "Val" "4u7")
    (property "Voltage" "")
    (property "ki_description" "SMD Multilayer Ceramic Capacitor, 4.7 µF, 10 V, 0402 [1005 Metric], ± 20%, X5R, GRM Series")
    (property "ki_keywords" "0402, SMT, CAPACITOR, PASSIVE")
    (attr smd)
    (fp_text reference "C219" (at 2.4 0) (layer "B.SilkS")
        (effects (font (size 0.7 0.7) (thickness 0.127)) (justify mirror))
    )
    (fp_text value "C_4u7_0402" (at 0 -1.17) (layer "B.Fab")
        (effects (font (size 1 1) (thickness 0.15)) (justify mirror))
    )
    (fp_text user "${REFERENCE}" (at 0 0) (layer "B.Fab")
        (effects (font (size 0.25 0.25) (thickness 0.04)) (justify mirror))
    )
    (fp_text user "Author: Antmicro" (at -0.939 -3.399 180) (layer "B.Fab") hide
        (effects (font (size 0.7 0.7) (thickness 0.15)) (justify left bottom mirror))
    )
    (fp_text user "License: Apache-2.0" (at -0.939 -5.799 180) (layer "B.Fab") hide
        (effects (font (size 0.7 0.7) (thickness 0.15)) (justify left bottom mirror))
    )
    (fp_rect (start -0.925 0.47) (end 0.925 -0.47)
      (stroke (width 0.05) (type default)) (fill none) (layer "B.CrtYd"))
    (fp_line (start -0.494 -0.248) (end -0.494 0.25)
      (stroke (width 0.15) (type solid)) (layer "B.Fab"))
    (fp_line (start -0.494 0.25) (end 0.504 0.25)
      (stroke (width 0.15) (type solid)) (layer "B.Fab"))
    (fp_line (start 0.504 -0.248) (end -0.494 -0.248)
      (stroke (width 0.15) (type solid)) (layer "B.Fab"))
    (fp_line (start 0.504 0.25) (end 0.504 -0.248)
      (stroke (width 0.15) (type solid)) (layer "B.Fab"))
    (pad "1" smd roundrect (at -0.48 0) (size 0.59 0.64) (layers "B.Cu" "B.Paste" "B.Mask") (roundrect_rratio 0.25)
      (net 218 "VCC1V8") (pintype "passive"))
    (pad "2" smd roundrect (at 0.48 0) (size 0.59 0.64) (layers "B.Cu" "B.Paste" "B.Mask") (roundrect_rratio 0.25)
      (net 1 "GND") (pintype "passive"))
  )
	(footprint "antmicro-footprints:C_0402_1005Metric" (layer "B.Cu")
    (at 97.6 126.65 180)
    (descr "Capacitor SMD 0402")
    (tags "capacitor SMD 0402")
    (property "Author" "Antmicro")
    (property "Dielectric" "")
    (property "License" "Apache-2.0")
    (property "MPN" "C1005X5R1E474M050BB")
    (property "Manufacturer" "TDK")
    (property "Public" "False")
    (property "Sheetfile" "fpga-banks.kicad_sch")
    (property "Sheetname" "FPGA banks")
    (property "Val" "470n")
    (property "Voltage" "")
    (property "ki_description" "SMD Multilayer Ceramic Capacitor, 0.47 µF, 25 V, 0402 [1005 Metric], ± 20%, X5R, C")
    (property "ki_keywords" "0402, SMT, CAPACITOR, PASSIVE, CERAMIC, MLCC")
    (attr smd)
    (fp_text reference "C220" (at 2.3 -0.2) (layer "B.SilkS")
        (effects (font (size 0.7 0.7) (thickness 0.127)) (justify mirror))
    )
    (fp_text value "C_470n_0402" (at 0 -1.17) (layer "B.Fab")
        (effects (font (size 1 1) (thickness 0.15)) (justify mirror))
    )
    (fp_text user "${REFERENCE}" (at 0 0) (layer "B.Fab")
        (effects (font (size 0.25 0.25) (thickness 0.04)) (justify mirror))
    )
    (fp_text user "Author: Antmicro" (at -0.939 -3.399) (layer "B.Fab") hide
        (effects (font (size 0.7 0.7) (thickness 0.15)) (justify left bottom mirror))
    )
    (fp_text user "License: Apache-2.0" (at -0.939 -5.799) (layer "B.Fab") hide
        (effects (font (size 0.7 0.7) (thickness 0.15)) (justify left bottom mirror))
    )
    (fp_rect (start -0.925 0.47) (end 0.925 -0.47)
      (stroke (width 0.05) (type default)) (fill none) (layer "B.CrtYd"))
    (fp_line (start -0.494 -0.248) (end -0.494 0.25)
      (stroke (width 0.15) (type solid)) (layer "B.Fab"))
    (fp_line (start -0.494 0.25) (end 0.504 0.25)
      (stroke (width 0.15) (type solid)) (layer "B.Fab"))
    (fp_line (start 0.504 -0.248) (end -0.494 -0.248)
      (stroke (width 0.15) (type solid)) (layer "B.Fab"))
    (fp_line (start 0.504 0.25) (end 0.504 -0.248)
      (stroke (width 0.15) (type solid)) (layer "B.Fab"))
    (pad "1" smd roundrect (at -0.48 0 180) (size 0.59 0.64) (layers "B.Cu" "B.Paste" "B.Mask") (roundrect_rratio 0.25)
      (net 2 "VCC3V3") (pintype "passive"))
    (pad "2" smd roundrect (at 0.48 0 180) (size 0.59 0.64) (layers "B.Cu" "B.Paste" "B.Mask") (roundrect_rratio 0.25)
      (net 1 "GND") (pintype "passive"))
  )
)
